(kicad_pcb
	(version 20260206)
	(generator "pcbnew")
	(generator_version "10.0")
	(general
		(thickness 1.6)
		(legacy_teardrops no)
	)
	(paper "A4")
	(title_block
		(title "03242023_DA0F0TMBIJ0_F0T_Motherboard_J_brd_V01_OCP.brd")
		(comment 1 "Grand Teton / footprints 2530-2536 of 6105")
	)
	(layers
		(0 "F.Cu" signal "TOP")
		(4 "In1.Cu" signal "GND")
		(6 "In2.Cu" signal "IN1")
		(8 "In3.Cu" signal "GND1")
		(10 "In4.Cu" signal "IN2")
		(12 "In5.Cu" signal "GND2")
		(14 "In6.Cu" signal "IN3")
		(16 "In7.Cu" signal "GND3")
		(18 "In8.Cu" signal "VCC")
		(20 "In9.Cu" signal "VCC1")
		(22 "In10.Cu" signal "GND4")
		(24 "In11.Cu" signal "IN4")
		(26 "In12.Cu" signal "GND5")
		(28 "In13.Cu" signal "IN5")
		(30 "In14.Cu" signal "GND6")
		(32 "In15.Cu" signal "IN6")
		(34 "In16.Cu" signal "GND7")
		(2 "B.Cu" signal "BOTTOM")
		(9 "F.Adhes" user "F.Adhesive")
		(11 "B.Adhes" user "B.Adhesive")
		(13 "F.Paste" user "Package Geometry/Pastemask Top")
		(15 "B.Paste" user "Package Geometry/Pastemask Bottom")
		(5 "F.SilkS" user "Ref Des/Silkscreen Top")
		(7 "B.SilkS" user "Ref Des/Silkscreen Bottom")
		(1 "F.Mask" user "Board Geometry/Soldermask Top")
		(3 "B.Mask" user "Board Geometry/Soldermask Bottom")
		(17 "Dwgs.User" user "User.Drawings")
		(19 "Cmts.User" user "User.Comments")
		(21 "Eco1.User" user "User.Eco1")
		(23 "Eco2.User" user "User.Eco2")
		(25 "Edge.Cuts" user "Board Geometry/Outline")
		(27 "Margin" user)
		(31 "F.CrtYd" user "Package Geometry/Place Bound Top")
		(29 "B.CrtYd" user "Package Geometry/Place Bound Bottom")
		(35 "F.Fab" user "Ref Des/Assembly Top")
		(33 "B.Fab" user "Ref Des/Assembly Bottom")
	)
	(footprint ""
		(layer "F.Cu")
		(at 243.78666 -253.363984)
		(property "Reference" "R4082"
			(at 0 0 0)
			(layer "F.SilkS")
			(hide yes)
			(effects
				(font
					(size 1.27 1.27)
				)
			)
		)
		(property "Value" ""
			(at 0 0 0)
			(layer "F.Fab")
			(effects
				(font
					(size 1.27 1.27)
				)
			)
		)
		(duplicate_pad_numbers_are_jumpers no)
		(fp_line
			(start -0.7874 -0.4064)
			(end 0.7874 -0.4064)
			(stroke
				(width 0.1524)
				(type default)
			)
			(layer "F.SilkS")
		)
		(fp_line
			(start -0.7874 0.4064)
			(end -0.7874 -0.4064)
			(stroke
				(width 0.1524)
				(type default)
			)
			(layer "F.SilkS")
		)
		(fp_line
			(start 0.7874 -0.4064)
			(end 0.7874 0.4064)
			(stroke
				(width 0.1524)
				(type default)
			)
			(layer "F.SilkS")
		)
		(fp_line
			(start 0.7874 0.4064)
			(end -0.7874 0.4064)
			(stroke
				(width 0.1524)
				(type default)
			)
			(layer "F.SilkS")
		)
		(fp_line
			(start -0.67945 -0.305054)
			(end -0.12065 -0.305054)
			(stroke
				(width 0.1)
				(type default)
			)
			(layer "F.Fab")
		)
		(fp_line
			(start -0.67945 0.3048)
			(end -0.67945 -0.305054)
			(stroke
				(width 0.1)
				(type default)
			)
			(layer "F.Fab")
		)
		(fp_line
			(start -0.12065 -0.305054)
			(end -0.12065 -0.2794)
			(stroke
				(width 0.1)
				(type default)
			)
			(layer "F.Fab")
		)
		(fp_line
			(start -0.12065 -0.2794)
			(end 0.12065 -0.2794)
			(stroke
				(width 0.1)
				(type default)
			)
			(layer "F.Fab")
		)
		(fp_line
			(start -0.12065 0.2794)
			(end -0.12065 0.3048)
			(stroke
				(width 0.1)
				(type default)
			)
			(layer "F.Fab")
		)
		(fp_line
			(start -0.12065 0.3048)
			(end -0.67945 0.3048)
			(stroke
				(width 0.1)
				(type default)
			)
			(layer "F.Fab")
		)
		(fp_line
			(start 0.120396 0.2794)
			(end -0.12065 0.2794)
			(stroke
				(width 0.1)
				(type default)
			)
			(layer "F.Fab")
		)
		(fp_line
			(start 0.120396 0.3048)
			(end 0.120396 0.2794)
			(stroke
				(width 0.1)
				(type default)
			)
			(layer "F.Fab")
		)
		(fp_line
			(start 0.12065 -0.3048)
			(end 0.67945 -0.3048)
			(stroke
				(width 0.1)
				(type default)
			)
			(layer "F.Fab")
		)
		(fp_line
			(start 0.12065 -0.2794)
			(end 0.12065 -0.3048)
			(stroke
				(width 0.1)
				(type default)
			)
			(layer "F.Fab")
		)
		(fp_line
			(start 0.67945 -0.3048)
			(end 0.67945 0.3048)
			(stroke
				(width 0.1)
				(type default)
			)
			(layer "F.Fab")
		)
		(fp_line
			(start 0.67945 0.3048)
			(end 0.120396 0.3048)
			(stroke
				(width 0.1)
				(type default)
			)
			(layer "F.Fab")
		)
		(pad "1" smd circle
			(at -0.40005 0)
			(size 0 0)
			(layers "F.Cu" "F.Mask" "F.Paste")
			(net "CLK_GEN2_SMB_SADR")
		)
		(pad "2" smd circle
			(at 0.40005 0)
			(size 0 0)
			(layers "F.Cu" "F.Mask" "F.Paste")
			(net "GND")
		)
	)
	(footprint ""
		(layer "F.Cu")
		(at 44.295822 -172.301916)
		(property "Reference" "PC460"
			(at 0 0 0)
			(layer "F.SilkS")
			(hide yes)
			(effects
				(font
					(size 1.27 1.27)
				)
			)
		)
		(property "Value" ""
			(at 0 0 0)
			(layer "F.Fab")
			(effects
				(font
					(size 1.27 1.27)
				)
			)
		)
		(duplicate_pad_numbers_are_jumpers no)
		(fp_line
			(start -3.400044 1.249934)
			(end 3.400044 1.249934)
			(stroke
				(width 0.1524)
				(type default)
			)
			(layer "F.SilkS")
		)
		(fp_circle
			(center 0 1.249934)
			(end 3.400044 1.249934)
			(stroke
				(width 0.1524)
				(type default)
			)
			(fill no)
			(layer "F.SilkS")
		)
		(fp_poly
			(pts
				(arc
					(start -3.400044 1.249934)
					(mid 0 4.649978)
					(end 3.400044 1.249934)
				)
			)
			(stroke
				(width 0)
				(type default)
			)
			(fill yes)
			(layer "F.SilkS")
		)
		(fp_circle
			(center 0 1.249934)
			(end 3.400044 1.249934)
			(stroke
				(width 0.1)
				(type default)
			)
			(fill no)
			(layer "F.Fab")
		)
		(pad "1" thru_hole rect
			(at 0 0)
			(size 1.524 1.524)
			(drill 1.016)
			(layers "*.Cu" "*.Mask")
			(remove_unused_layers no)
			(net "SW_P12V_PVCCINFAON_CPU1_FLT")
			(clearance 0)
			(padstack
				(mode front_inner_back)
				(layer "Inner"
					(shape circle)
					(size 1.524 1.524)
					(clearance 0)
				)
				(layer "B.Cu"
					(shape rect)
					(size 1.524 1.524)
					(clearance 0)
				)
			)
		)
		(pad "2" thru_hole circle
			(at 0 2.500122)
			(size 1.524 1.524)
			(drill 1.016)
			(layers "*.Cu" "*.Mask")
			(remove_unused_layers no)
			(net "GND")
			(clearance 0)
		)
	)
	(footprint ""
		(layer "F.Cu")
		(at 119.333264 -354.737924 180)
		(property "Reference" "R2380"
			(at 0 0 180)
			(layer "F.SilkS")
			(hide yes)
			(effects
				(font
					(size 1.27 1.27)
				)
			)
		)
		(property "Value" ""
			(at 0 0 180)
			(layer "F.Fab")
			(effects
				(font
					(size 1.27 1.27)
				)
			)
		)
		(duplicate_pad_numbers_are_jumpers no)
		(fp_line
			(start 0.7874 0.4064)
			(end -0.7874 0.4064)
			(stroke
				(width 0.1524)
				(type default)
			)
			(layer "F.SilkS")
		)
		(fp_line
			(start 0.7874 -0.4064)
			(end 0.7874 0.4064)
			(stroke
				(width 0.1524)
				(type default)
			)
			(layer "F.SilkS")
		)
		(fp_line
			(start -0.7874 0.4064)
			(end -0.7874 -0.4064)
			(stroke
				(width 0.1524)
				(type default)
			)
			(layer "F.SilkS")
		)
		(fp_line
			(start -0.7874 -0.4064)
			(end 0.7874 -0.4064)
			(stroke
				(width 0.1524)
				(type default)
			)
			(layer "F.SilkS")
		)
		(fp_line
			(start 0.67945 0.3048)
			(end 0.120396 0.3048)
			(stroke
				(width 0.1)
				(type default)
			)
			(layer "F.Fab")
		)
		(fp_line
			(start 0.67945 -0.3048)
			(end 0.67945 0.3048)
			(stroke
				(width 0.1)
				(type default)
			)
			(layer "F.Fab")
		)
		(fp_line
			(start 0.12065 -0.2794)
			(end 0.12065 -0.3048)
			(stroke
				(width 0.1)
				(type default)
			)
			(layer "F.Fab")
		)
		(fp_line
			(start 0.12065 -0.3048)
			(end 0.67945 -0.3048)
			(stroke
				(width 0.1)
				(type default)
			)
			(layer "F.Fab")
		)
		(fp_line
			(start 0.120396 0.3048)
			(end 0.120396 0.2794)
			(stroke
				(width 0.1)
				(type default)
			)
			(layer "F.Fab")
		)
		(fp_line
			(start 0.120396 0.2794)
			(end -0.12065 0.2794)
			(stroke
				(width 0.1)
				(type default)
			)
			(layer "F.Fab")
		)
		(fp_line
			(start -0.12065 0.3048)
			(end -0.67945 0.3048)
			(stroke
				(width 0.1)
				(type default)
			)
			(layer "F.Fab")
		)
		(fp_line
			(start -0.12065 0.2794)
			(end -0.12065 0.3048)
			(stroke
				(width 0.1)
				(type default)
			)
			(layer "F.Fab")
		)
		(fp_line
			(start -0.12065 -0.2794)
			(end 0.12065 -0.2794)
			(stroke
				(width 0.1)
				(type default)
			)
			(layer "F.Fab")
		)
		(fp_line
			(start -0.12065 -0.305054)
			(end -0.12065 -0.2794)
			(stroke
				(width 0.1)
				(type default)
			)
			(layer "F.Fab")
		)
		(fp_line
			(start -0.67945 0.3048)
			(end -0.67945 -0.305054)
			(stroke
				(width 0.1)
				(type default)
			)
			(layer "F.Fab")
		)
		(fp_line
			(start -0.67945 -0.305054)
			(end -0.12065 -0.305054)
			(stroke
				(width 0.1)
				(type default)
			)
			(layer "F.Fab")
		)
		(pad "1" smd circle
			(at -0.40005 0 180)
			(size 0 0)
			(layers "F.Cu" "F.Mask" "F.Paste")
			(net "PWRGD_PVPP_HBM_CPU1_R")
		)
		(pad "2" smd circle
			(at 0.40005 0 180)
			(size 0 0)
			(layers "F.Cu" "F.Mask" "F.Paste")
			(net "PWRGD_PVPP_HBM_CPU1")
		)
	)
	(footprint ""
		(layer "F.Cu")
		(at 172.047408 -415.900362 180)
		(property "Reference" "Q103"
			(at 1.022096 1.8669 0)
			(unlocked yes)
			(layer "F.SilkS")
			(effects
				(font
					(size 0.7874 0.5842)
					(thickness 0.1524)
				)
				(justify left)
			)
		)
		(property "Value" ""
			(at 0 0 180)
			(layer "F.Fab")
			(effects
				(font
					(size 1.27 1.27)
				)
			)
		)
		(duplicate_pad_numbers_are_jumpers no)
		(fp_line
			(start 1.332738 1.100074)
			(end -1.332738 1.100074)
			(stroke
				(width 0.1524)
				(type default)
			)
			(layer "F.SilkS")
		)
		(fp_line
			(start 1.332738 -1.100074)
			(end 1.332738 1.100074)
			(stroke
				(width 0.1524)
				(type default)
			)
			(layer "F.SilkS")
		)
		(fp_line
			(start 0.4826 -1.100074)
			(end 1.332738 -1.100074)
			(stroke
				(width 0.1524)
				(type default)
			)
			(layer "F.SilkS")
		)
		(fp_line
			(start 0 -0.541274)
			(end 0.4826 -1.100074)
			(stroke
				(width 0.1524)
				(type default)
			)
			(layer "F.SilkS")
		)
		(fp_line
			(start -0.4826 -1.100074)
			(end 0 -0.541274)
			(stroke
				(width 0.1524)
				(type default)
			)
			(layer "F.SilkS")
		)
		(fp_line
			(start -1.332738 1.100074)
			(end -1.332738 -1.100074)
			(stroke
				(width 0.1524)
				(type default)
			)
			(layer "F.SilkS")
		)
		(fp_line
			(start -1.332738 -1.100074)
			(end -0.4826 -1.100074)
			(stroke
				(width 0.1524)
				(type default)
			)
			(layer "F.SilkS")
		)
		(fp_poly
			(pts
				(xy -0.675132 -1.928622) (xy -1.02616 -1.226566) (xy -1.377188 -1.928622)
			)
			(stroke
				(width 0)
				(type default)
			)
			(fill yes)
			(layer "F.SilkS")
		)
		(fp_line
			(start 0.674878 1.100074)
			(end -0.674878 1.100074)
			(stroke
				(width 0.1)
				(type default)
			)
			(layer "F.Fab")
		)
		(fp_line
			(start 0.674878 -1.100074)
			(end 0.674878 1.100074)
			(stroke
				(width 0.1)
				(type default)
			)
			(layer "F.Fab")
		)
		(fp_line
			(start -0.674878 1.100074)
			(end -0.674878 -1.100074)
			(stroke
				(width 0.1)
				(type default)
			)
			(layer "F.Fab")
		)
		(fp_line
			(start -0.674878 -1.100074)
			(end 0.674878 -1.100074)
			(stroke
				(width 0.1)
				(type default)
			)
			(layer "F.Fab")
		)
		(fp_poly
			(pts
				(xy -2.2352 -0.298958) (xy -2.2352 -1.001014) (xy -1.533144 -0.649986)
			)
			(stroke
				(width 0)
				(type default)
			)
			(fill yes)
			(layer "F.Fab")
		)
		(pad "1" smd rect
			(at -0.94996 -0.649986 270)
			(size 0.4318 0.508)
			(layers "F.Cu" "F.Mask" "F.Paste")
			(net "GND")
		)
		(pad "2" smd rect
			(at -0.94996 0 270)
			(size 0.4318 0.508)
			(layers "F.Cu" "F.Mask" "F.Paste")
			(net "GPU_HMC_PRSNT_N")
		)
		(pad "3" smd rect
			(at -0.94996 0.649986 270)
			(size 0.4318 0.508)
			(layers "F.Cu" "F.Mask" "F.Paste")
			(net "GPU_HMC_PRSNT_ISO_N")
		)
		(pad "4" smd rect
			(at 0.94996 0.649986 270)
			(size 0.4318 0.508)
			(layers "F.Cu" "F.Mask" "F.Paste")
			(net "GND")
		)
		(pad "5" smd rect
			(at 0.94996 0 270)
			(size 0.4318 0.508)
			(layers "F.Cu" "F.Mask" "F.Paste")
			(net "GPU_HMC_PRSNT")
		)
		(pad "6" smd rect
			(at 0.94996 -0.649986 270)
			(size 0.4318 0.508)
			(layers "F.Cu" "F.Mask" "F.Paste")
			(net "GPU_HMC_PRSNT")
		)
	)
	(footprint ""
		(layer "F.Cu")
		(at 194.856608 -401.800822 180)
		(property "Reference" "PR3918"
			(at 0 0 180)
			(layer "F.SilkS")
			(hide yes)
			(effects
				(font
					(size 1.27 1.27)
				)
			)
		)
		(property "Value" ""
			(at 0 0 180)
			(layer "F.Fab")
			(effects
				(font
					(size 1.27 1.27)
				)
			)
		)
		(duplicate_pad_numbers_are_jumpers no)
		(fp_line
			(start 0.7874 0.4064)
			(end -0.7874 0.4064)
			(stroke
				(width 0.1524)
				(type default)
			)
			(layer "F.SilkS")
		)
		(fp_line
			(start 0.7874 -0.4064)
			(end 0.7874 0.4064)
			(stroke
				(width 0.1524)
				(type default)
			)
			(layer "F.SilkS")
		)
		(fp_line
			(start -0.7874 0.4064)
			(end -0.7874 -0.4064)
			(stroke
				(width 0.1524)
				(type default)
			)
			(layer "F.SilkS")
		)
		(fp_line
			(start -0.7874 -0.4064)
			(end 0.7874 -0.4064)
			(stroke
				(width 0.1524)
				(type default)
			)
			(layer "F.SilkS")
		)
		(fp_line
			(start 0.67945 0.3048)
			(end 0.120396 0.3048)
			(stroke
				(width 0.1)
				(type default)
			)
			(layer "F.Fab")
		)
		(fp_line
			(start 0.67945 -0.3048)
			(end 0.67945 0.3048)
			(stroke
				(width 0.1)
				(type default)
			)
			(layer "F.Fab")
		)
		(fp_line
			(start 0.12065 -0.2794)
			(end 0.12065 -0.3048)
			(stroke
				(width 0.1)
				(type default)
			)
			(layer "F.Fab")
		)
		(fp_line
			(start 0.12065 -0.3048)
			(end 0.67945 -0.3048)
			(stroke
				(width 0.1)
				(type default)
			)
			(layer "F.Fab")
		)
		(fp_line
			(start 0.120396 0.3048)
			(end 0.120396 0.2794)
			(stroke
				(width 0.1)
				(type default)
			)
			(layer "F.Fab")
		)
		(fp_line
			(start 0.120396 0.2794)
			(end -0.12065 0.2794)
			(stroke
				(width 0.1)
				(type default)
			)
			(layer "F.Fab")
		)
		(fp_line
			(start -0.12065 0.3048)
			(end -0.67945 0.3048)
			(stroke
				(width 0.1)
				(type default)
			)
			(layer "F.Fab")
		)
		(fp_line
			(start -0.12065 0.2794)
			(end -0.12065 0.3048)
			(stroke
				(width 0.1)
				(type default)
			)
			(layer "F.Fab")
		)
		(fp_line
			(start -0.12065 -0.2794)
			(end 0.12065 -0.2794)
			(stroke
				(width 0.1)
				(type default)
			)
			(layer "F.Fab")
		)
		(fp_line
			(start -0.12065 -0.305054)
			(end -0.12065 -0.2794)
			(stroke
				(width 0.1)
				(type default)
			)
			(layer "F.Fab")
		)
		(fp_line
			(start -0.67945 0.3048)
			(end -0.67945 -0.305054)
			(stroke
				(width 0.1)
				(type default)
			)
			(layer "F.Fab")
		)
		(fp_line
			(start -0.67945 -0.305054)
			(end -0.12065 -0.305054)
			(stroke
				(width 0.1)
				(type default)
			)
			(layer "F.Fab")
		)
		(pad "1" smd circle
			(at -0.40005 0 180)
			(size 0 0)
			(layers "F.Cu" "F.Mask" "F.Paste")
			(net "HSC_IMON")
		)
		(pad "2" smd circle
			(at 0.40005 0 180)
			(size 0 0)
			(layers "F.Cu" "F.Mask" "F.Paste")
			(net "AGND_HSC")
		)
	)
	(footprint ""
		(layer "F.Cu")
		(at 165.275514 -408.517344 -90)
		(property "Reference" "C1545"
			(at 0 0 270)
			(layer "F.SilkS")
			(hide yes)
			(effects
				(font
					(size 1.27 1.27)
				)
			)
		)
		(property "Value" ""
			(at 0 0 270)
			(layer "F.Fab")
			(effects
				(font
					(size 1.27 1.27)
				)
			)
		)
		(duplicate_pad_numbers_are_jumpers no)
		(fp_line
			(start -0.299974 0.150114)
			(end -0.299974 -0.150114)
			(stroke
				(width 0.1)
				(type default)
			)
			(layer "F.Fab")
		)
		(fp_line
			(start 0.299974 0.150114)
			(end -0.299974 0.150114)
			(stroke
				(width 0.1)
				(type default)
			)
			(layer "F.Fab")
		)
		(fp_line
			(start -0.299974 -0.150114)
			(end 0.299974 -0.150114)
			(stroke
				(width 0.1)
				(type default)
			)
			(layer "F.Fab")
		)
		(fp_line
			(start 0.299974 -0.150114)
			(end 0.299974 0.150114)
			(stroke
				(width 0.1)
				(type default)
			)
			(layer "F.Fab")
		)
		(pad "1" smd rect
			(at -0.2667 0 270)
			(size 0.3048 0.381)
			(layers "F.Cu" "F.Mask" "F.Paste")
			(net "P5E_CPU1_PE3_TX_C_DP<1>")
		)
		(pad "2" smd rect
			(at 0.2667 0 270)
			(size 0.3048 0.381)
			(layers "F.Cu" "F.Mask" "F.Paste")
			(net "P5E_CPU1_PE3_TX_DP<1>")
		)
	)
	(footprint ""
		(layer "F.Cu")
		(at 341.339932 -333.525368 -90)
		(property "Reference" "PC295_P0_1"
			(at 0 0 270)
			(layer "F.SilkS")
			(hide yes)
			(effects
				(font
					(size 1.27 1.27)
				)
			)
		)
		(property "Value" ""
			(at 0 0 270)
			(layer "F.Fab")
			(effects
				(font
					(size 1.27 1.27)
				)
			)
		)
		(duplicate_pad_numbers_are_jumpers no)
		(fp_line
			(start -0.7874 0.4064)
			(end -0.7874 -0.4064)
			(stroke
				(width 0.1524)
				(type default)
			)
			(layer "F.SilkS")
		)
		(fp_line
			(start 0.7874 0.4064)
			(end -0.7874 0.4064)
			(stroke
				(width 0.1524)
				(type default)
			)
			(layer "F.SilkS")
		)
		(fp_line
			(start -0.7874 -0.4064)
			(end 0.7874 -0.4064)
			(stroke
				(width 0.1524)
				(type default)
			)
			(layer "F.SilkS")
		)
		(fp_line
			(start 0.7874 -0.4064)
			(end 0.7874 0.4064)
			(stroke
				(width 0.1524)
				(type default)
			)
			(layer "F.SilkS")
		)
		(fp_line
			(start -0.67945 0.3048)
			(end -0.67945 -0.305054)
			(stroke
				(width 0.1)
				(type default)
			)
			(layer "F.Fab")
		)
		(fp_line
			(start -0.12065 0.3048)
			(end -0.67945 0.3048)
			(stroke
				(width 0.1)
				(type default)
			)
			(layer "F.Fab")
		)
		(fp_line
			(start 0.120396 0.3048)
			(end 0.120396 0.2794)
			(stroke
				(width 0.1)
				(type default)
			)
			(layer "F.Fab")
		)
		(fp_line
			(start 0.67945 0.3048)
			(end 0.120396 0.3048)
			(stroke
				(width 0.1)
				(type default)
			)
			(layer "F.Fab")
		)
		(fp_line
			(start -0.12065 0.2794)
			(end -0.12065 0.3048)
			(stroke
				(width 0.1)
				(type default)
			)
			(layer "F.Fab")
		)
		(fp_line
			(start 0.120396 0.2794)
			(end -0.12065 0.2794)
			(stroke
				(width 0.1)
				(type default)
			)
			(layer "F.Fab")
		)
		(fp_line
			(start -0.12065 -0.2794)
			(end 0.12065 -0.2794)
			(stroke
				(width 0.1)
				(type default)
			)
			(layer "F.Fab")
		)
		(fp_line
			(start 0.12065 -0.2794)
			(end 0.12065 -0.3048)
			(stroke
				(width 0.1)
				(type default)
			)
			(layer "F.Fab")
		)
		(fp_line
			(start 0.12065 -0.3048)
			(end 0.67945 -0.3048)
			(stroke
				(width 0.1)
				(type default)
			)
			(layer "F.Fab")
		)
		(fp_line
			(start 0.67945 -0.3048)
			(end 0.67945 0.3048)
			(stroke
				(width 0.1)
				(type default)
			)
			(layer "F.Fab")
		)
		(fp_line
			(start -0.67945 -0.305054)
			(end -0.12065 -0.305054)
			(stroke
				(width 0.1)
				(type default)
			)
			(layer "F.Fab")
		)
		(fp_line
			(start -0.12065 -0.305054)
			(end -0.12065 -0.2794)
			(stroke
				(width 0.1)
				(type default)
			)
			(layer "F.Fab")
		)
		(pad "1" smd circle
			(at -0.40005 0 270)
			(size 0 0)
			(layers "F.Cu" "F.Mask" "F.Paste")
			(net "PVCCIN_CPU0_PVCC")
		)
		(pad "2" smd circle
			(at 0.40005 0 270)
			(size 0 0)
			(layers "F.Cu" "F.Mask" "F.Paste")
			(net "GND")
		)
	)
)
